# T6G (Grand Teton) — schematic netlist excerpt (pin names and nets, part order shuffled) for the footprints in the layout excerpt that follows; sources: Cadence DE-HDL packaged netlist, KiCad conversion of 04192023_DAF0TMB3IC0_F0TG_MB_C_brd_V02_OCP.brd

R4638  Q_RES  243 1% CHIP  pkg 1206LF  page 188 : A = P5V ; B = VR_P5V_EN_D
C472  Q_CAP  4.7UF 6.3V 20% X6S  pkg 0402  page 356 : A = P0V9_CPU1_RT3_2A ; B = GND
R3173  Q_RES  1K 1% CHIP  pkg 0402LF  page 137 : A = SGPIO_OCP_V3_2_LD_N ; B = P3V3_OCP_V3_2

(kicad_pcb
	(version 20260206)
	(generator "pcbnew")
	(generator_version "10.0")
	(general
		(thickness 1.6)
		(legacy_teardrops no)
	)
	(paper "A4")
	(title_block
		(title "04192023_DAF0TMB3IC0_F0TG_MB_C_brd_V02_OCP.brd")
		(comment 1 "Grand Teton / footprints 6780-6782 of 8354")
	)
	(layers
		(0 "F.Cu" signal "TOP")
		(4 "In1.Cu" signal "GND")
		(6 "In2.Cu" signal "IN1")
		(8 "In3.Cu" signal "GND1")
		(10 "In4.Cu" signal "IN2")
		(12 "In5.Cu" signal "GND2")
		(14 "In6.Cu" signal "IN3")
		(16 "In7.Cu" signal "GND3")
		(18 "In8.Cu" signal "VCC")
		(20 "In9.Cu" signal "VCC1")
		(22 "In10.Cu" signal "GND4")
		(24 "In11.Cu" signal "IN4")
		(26 "In12.Cu" signal "GND5")
		(28 "In13.Cu" signal "IN5")
		(30 "In14.Cu" signal "GND6")
		(32 "In15.Cu" signal "IN6")
		(34 "In16.Cu" signal "GND7")
		(2 "B.Cu" signal "BOTTOM")
		(9 "F.Adhes" user "F.Adhesive")
		(11 "B.Adhes" user "B.Adhesive")
		(13 "F.Paste" user "Package Geometry/Pastemask Top")
		(15 "B.Paste" user "Package Geometry/Pastemask Bottom")
		(5 "F.SilkS" user "Ref Des/Silkscreen Top")
		(7 "B.SilkS" user "Ref Des/Silkscreen Bottom")
		(1 "F.Mask" user "Board Geometry/Soldermask Top")
		(3 "B.Mask" user "Board Geometry/Soldermask Bottom")
		(17 "Dwgs.User" user "User.Drawings")
		(19 "Cmts.User" user "User.Comments")
		(21 "Eco1.User" user "User.Eco1")
		(23 "Eco2.User" user "User.Eco2")
		(25 "Edge.Cuts" user "Board Geometry/Outline")
		(27 "Margin" user)
		(31 "F.CrtYd" user "Package Geometry/Place Bound Top")
		(29 "B.CrtYd" user "Package Geometry/Place Bound Bottom")
		(35 "F.Fab" user "Ref Des/Assembly Top")
		(33 "B.Fab" user "Ref Des/Assembly Bottom")
	)
	(footprint ""
		(layer "B.Cu")
		(at 116.891308 -390.560052 90)
		(property "Reference" "C472"
			(at 0 0 90)
			(layer "B.SilkS")
			(hide yes)
			(effects
				(font
					(size 1.27 1.27)
				)
				(justify mirror)
			)
		)
		(property "Value" ""
			(at 0 0 90)
			(layer "B.Fab")
			(effects
				(font
					(size 1.27 1.27)
				)
				(justify mirror)
			)
		)
		(duplicate_pad_numbers_are_jumpers no)
		(fp_line
			(start 0.7874 -0.4064)
			(end -0.7874 -0.4064)
			(stroke
				(width 0.1524)
				(type default)
			)
			(layer "B.SilkS")
		)
		(fp_line
			(start -0.7874 -0.4064)
			(end -0.7874 0.4064)
			(stroke
				(width 0.1524)
				(type default)
			)
			(layer "B.SilkS")
		)
		(fp_line
			(start 0.7874 0.4064)
			(end 0.7874 -0.4064)
			(stroke
				(width 0.1524)
				(type default)
			)
			(layer "B.SilkS")
		)
		(fp_line
			(start -0.7874 0.4064)
			(end 0.7874 0.4064)
			(stroke
				(width 0.1524)
				(type default)
			)
			(layer "B.SilkS")
		)
		(fp_line
			(start 0.67945 -0.305054)
			(end 0.12065 -0.305054)
			(stroke
				(width 0.1)
				(type default)
			)
			(layer "B.Fab")
		)
		(fp_line
			(start 0.12065 -0.305054)
			(end 0.12065 -0.2794)
			(stroke
				(width 0.1)
				(type default)
			)
			(layer "B.Fab")
		)
		(fp_line
			(start -0.12065 -0.3048)
			(end -0.67945 -0.3048)
			(stroke
				(width 0.1)
				(type default)
			)
			(layer "B.Fab")
		)
		(fp_line
			(start -0.67945 -0.3048)
			(end -0.67945 0.3048)
			(stroke
				(width 0.1)
				(type default)
			)
			(layer "B.Fab")
		)
		(fp_line
			(start 0.12065 -0.2794)
			(end -0.12065 -0.2794)
			(stroke
				(width 0.1)
				(type default)
			)
			(layer "B.Fab")
		)
		(fp_line
			(start -0.12065 -0.2794)
			(end -0.12065 -0.3048)
			(stroke
				(width 0.1)
				(type default)
			)
			(layer "B.Fab")
		)
		(fp_line
			(start 0.12065 0.2794)
			(end 0.12065 0.3048)
			(stroke
				(width 0.1)
				(type default)
			)
			(layer "B.Fab")
		)
		(fp_line
			(start -0.120396 0.2794)
			(end 0.12065 0.2794)
			(stroke
				(width 0.1)
				(type default)
			)
			(layer "B.Fab")
		)
		(fp_line
			(start 0.67945 0.3048)
			(end 0.67945 -0.305054)
			(stroke
				(width 0.1)
				(type default)
			)
			(layer "B.Fab")
		)
		(fp_line
			(start 0.12065 0.3048)
			(end 0.67945 0.3048)
			(stroke
				(width 0.1)
				(type default)
			)
			(layer "B.Fab")
		)
		(fp_line
			(start -0.120396 0.3048)
			(end -0.120396 0.2794)
			(stroke
				(width 0.1)
				(type default)
			)
			(layer "B.Fab")
		)
		(fp_line
			(start -0.67945 0.3048)
			(end -0.120396 0.3048)
			(stroke
				(width 0.1)
				(type default)
			)
			(layer "B.Fab")
		)
		(pad "1" smd circle
			(at 0.40005 0 270)
			(size 0 0)
			(layers "B.Cu" "B.Mask" "B.Paste")
			(net "P0V9_CPU1_RT3_2A")
		)
		(pad "2" smd circle
			(at -0.40005 0 270)
			(size 0 0)
			(layers "B.Cu" "B.Mask" "B.Paste")
			(net "GND")
		)
	)
	(footprint ""
		(layer "B.Cu")
		(at 398.249902 -152.29078 -90)
		(property "Reference" "R4638"
			(at 0 0 90)
			(layer "B.SilkS")
			(hide yes)
			(effects
				(font
					(size 1.27 1.27)
				)
				(justify mirror)
			)
		)
		(property "Value" ""
			(at 0 0 90)
			(layer "B.Fab")
			(effects
				(font
					(size 1.27 1.27)
				)
				(justify mirror)
			)
		)
		(duplicate_pad_numbers_are_jumpers no)
		(fp_line
			(start -2.234946 0.9271)
			(end 2.234946 0.9271)
			(stroke
				(width 0.1524)
				(type default)
			)
			(layer "B.SilkS")
		)
		(fp_line
			(start 2.234946 0.9271)
			(end 2.234946 -0.9271)
			(stroke
				(width 0.1524)
				(type default)
			)
			(layer "B.SilkS")
		)
		(fp_line
			(start -2.234946 -0.9271)
			(end -2.234946 0.9271)
			(stroke
				(width 0.1524)
				(type default)
			)
			(layer "B.SilkS")
		)
		(fp_line
			(start 2.234946 -0.9271)
			(end -2.234946 -0.9271)
			(stroke
				(width 0.1524)
				(type default)
			)
			(layer "B.SilkS")
		)
		(fp_line
			(start -1.575054 0.824992)
			(end -1.575054 -0.824992)
			(stroke
				(width 0.1)
				(type default)
			)
			(layer "B.Fab")
		)
		(fp_line
			(start 1.575054 0.824992)
			(end -1.575054 0.824992)
			(stroke
				(width 0.1)
				(type default)
			)
			(layer "B.Fab")
		)
		(fp_line
			(start -1.575054 -0.824992)
			(end 1.575054 -0.824992)
			(stroke
				(width 0.1)
				(type default)
			)
			(layer "B.Fab")
		)
		(fp_line
			(start 1.575054 -0.824992)
			(end 1.575054 0.824992)
			(stroke
				(width 0.1)
				(type default)
			)
			(layer "B.Fab")
		)
		(pad "1" smd rect
			(at 1.599946 0 90)
			(size 1.016 1.6002)
			(layers "B.Cu" "B.Mask" "B.Paste")
			(net "P5V")
		)
		(pad "2" smd rect
			(at -1.599946 0 90)
			(size 1.016 1.6002)
			(layers "B.Cu" "B.Mask" "B.Paste")
			(net "VR_P5V_EN_D")
		)
	)
	(footprint ""
		(layer "B.Cu")
		(at 76.20508 -11.267948 90)
		(property "Reference" "R3173"
			(at 0 0 90)
			(layer "B.SilkS")
			(hide yes)
			(effects
				(font
					(size 1.27 1.27)
				)
				(justify mirror)
			)
		)
		(property "Value" ""
			(at 0 0 90)
			(layer "B.Fab")
			(effects
				(font
					(size 1.27 1.27)
				)
				(justify mirror)
			)
		)
		(duplicate_pad_numbers_are_jumpers no)
		(fp_line
			(start 0.7874 -0.4064)
			(end -0.7874 -0.4064)
			(stroke
				(width 0.1524)
				(type default)
			)
			(layer "B.SilkS")
		)
		(fp_line
			(start -0.7874 -0.4064)
			(end -0.7874 0.4064)
			(stroke
				(width 0.1524)
				(type default)
			)
			(layer "B.SilkS")
		)
		(fp_line
			(start 0.7874 0.4064)
			(end 0.7874 -0.4064)
			(stroke
				(width 0.1524)
				(type default)
			)
			(layer "B.SilkS")
		)
		(fp_line
			(start -0.7874 0.4064)
			(end 0.7874 0.4064)
			(stroke
				(width 0.1524)
				(type default)
			)
			(layer "B.SilkS")
		)
		(fp_line
			(start 0.67945 -0.305054)
			(end 0.12065 -0.305054)
			(stroke
				(width 0.1)
				(type default)
			)
			(layer "B.Fab")
		)
		(fp_line
			(start 0.12065 -0.305054)
			(end 0.12065 -0.2794)
			(stroke
				(width 0.1)
				(type default)
			)
			(layer "B.Fab")
		)
		(fp_line
			(start -0.12065 -0.3048)
			(end -0.67945 -0.3048)
			(stroke
				(width 0.1)
				(type default)
			)
			(layer "B.Fab")
		)
		(fp_line
			(start -0.67945 -0.3048)
			(end -0.67945 0.3048)
			(stroke
				(width 0.1)
				(type default)
			)
			(layer "B.Fab")
		)
		(fp_line
			(start 0.12065 -0.2794)
			(end -0.12065 -0.2794)
			(stroke
				(width 0.1)
				(type default)
			)
			(layer "B.Fab")
		)
		(fp_line
			(start -0.12065 -0.2794)
			(end -0.12065 -0.3048)
			(stroke
				(width 0.1)
				(type default)
			)
			(layer "B.Fab")
		)
		(fp_line
			(start 0.12065 0.2794)
			(end 0.12065 0.3048)
			(stroke
				(width 0.1)
				(type default)
			)
			(layer "B.Fab")
		)
		(fp_line
			(start -0.120396 0.2794)
			(end 0.12065 0.2794)
			(stroke
				(width 0.1)
				(type default)
			)
			(layer "B.Fab")
		)
		(fp_line
			(start 0.67945 0.3048)
			(end 0.67945 -0.305054)
			(stroke
				(width 0.1)
				(type default)
			)
			(layer "B.Fab")
		)
		(fp_line
			(start 0.12065 0.3048)
			(end 0.67945 0.3048)
			(stroke
				(width 0.1)
				(type default)
			)
			(layer "B.Fab")
		)
		(fp_line
			(start -0.120396 0.3048)
			(end -0.120396 0.2794)
			(stroke
				(width 0.1)
				(type default)
			)
			(layer "B.Fab")
		)
		(fp_line
			(start -0.67945 0.3048)
			(end -0.120396 0.3048)
			(stroke
				(width 0.1)
				(type default)
			)
			(layer "B.Fab")
		)
		(pad "1" smd circle
			(at 0.40005 0 270)
			(size 0 0)
			(layers "B.Cu" "B.Mask" "B.Paste")
			(net "SGPIO_OCP_V3_2_LD_N")
		)
		(pad "2" smd circle
			(at -0.40005 0 270)
			(size 0 0)
			(layers "B.Cu" "B.Mask" "B.Paste")
			(net "P3V3_OCP_V3_2")
		)
	)
)
